#ISCELL
  mstr_misc dns *
  *
#ISCELL
  pure_quanta quanta_title_block_c *
  *
#ISCELL
  standard offpage *
  page174_i1
#CELL
  pure_quanta q_res *
  page174_i10
#CELL
  pure_quanta q_res *
  page174_i11
#CELL
  pure_quanta q_cap *
  page174_i12
#ISCELL
  pure_quanta_power universal_gnd *
  page174_i13
#CELL
  pure_quanta q_cap *
  page174_i14
#CELL
  pure_quanta q_res *
  page174_i15
#ISCELL
  pure_quanta_power vcc_core *
  page174_i16
#ISCELL
  standard offpage *
  page174_i17
#ISCELL
  pure_quanta_power universal_gnd *
  page174_i18
#CELL
  pure_quanta q_cap *
  page174_i19
#CELL
  pure_quanta q_cap *
  page174_i2
#CELL
  pure_quanta q_res *
  page174_i20
#CELL
  pure_quanta q_cap *
  page174_i21
#CELL
  pure_quanta q_cap *
  page174_i22
#ISCELL
  pure_quanta_power universal_gnd *
  page174_i23
#CELL
  pure_quanta q_inductor *
  page174_i24
#CELL
  pure_quanta q_inductor4p_14 *
  page174_i25
#ISCELL
  standard offpage *
  page174_i26
#CELL
  pure_quanta q_cap *
  page174_i27
#ISCELL
  pure_quanta_power universal_gnd *
  page174_i28
#CELL
  pure_quanta q_cap *
  page174_i29
#ISCELL
  pure_quanta_power universal_gnd *
  page174_i3
#CELL
  pure_quanta q_cap *
  page174_i30
#CELL
  pure_quanta q_cap *
  page174_i31
#CELL
  pure_quanta q_cap *
  page174_i32
#ISCELL
  pure_quanta_power universal_gnd *
  page174_i33
#CELL
  pure_quanta q_cap *
  page174_i34
#ISCELL
  pure_quanta_power vcc_core *
  page174_i35
#ISCELL
  pure_quanta_power vcc_core *
  page174_i36
#CELL
  pure_quanta q_cap *
  page174_i37
#CELL
  pure_quanta isl99390frztr5935 *
  page174_i38
#ISCELL
  pure_quanta_power universal_gnd *
  page174_i4
#ISCELL
  standard offpage *
  page174_i5
#ISCELL
  standard offpage *
  page174_i6
#CELL
  pure_quanta q_res *
  page174_i7
#ISCELL
  pure_quanta_power universal_gnd *
  page174_i8
#ISCELL
  pure_quanta_power universal_gnd *
  page174_i9
